(kicad_pcb
	(version 20260206)
	(generator "pcbnew")
	(generator_version "10.0")
	(general
		(thickness 1.6)
		(legacy_teardrops no)
	)
	(paper "A4")
	(title_block
		(title "01162023_DA0F0TEBIF0_F0T_Expander_BD_F_brd_V02_OCP.brd")
		(comment 1 "Grand Teton / footprint 6619 of 9728 (PEX0), pads 1188-1304 of 2397")
	)
	(layers
		(0 "F.Cu" signal "TOP")
		(4 "In1.Cu" signal "GND")
		(6 "In2.Cu" signal "VCC")
		(8 "In3.Cu" signal "VCC1")
		(10 "In4.Cu" signal "GND1")
		(12 "In5.Cu" signal "IN1")
		(14 "In6.Cu" signal "GND2")
		(16 "In7.Cu" signal "IN2")
		(18 "In8.Cu" signal "GND3")
		(20 "In9.Cu" signal "IN3")
		(22 "In10.Cu" signal "GND4")
		(24 "In11.Cu" signal "IN4")
		(26 "In12.Cu" signal "GND5")
		(28 "In13.Cu" signal "IN5")
		(30 "In14.Cu" signal "GND6")
		(32 "In15.Cu" signal "IN6")
		(34 "In16.Cu" signal "GND7")
		(2 "B.Cu" signal "BOTTOM")
		(9 "F.Adhes" user "F.Adhesive")
		(11 "B.Adhes" user "B.Adhesive")
		(13 "F.Paste" user "Package Geometry/Pastemask Top")
		(15 "B.Paste" user "Package Geometry/Pastemask Bottom")
		(5 "F.SilkS" user "Ref Des/Silkscreen Top")
		(7 "B.SilkS" user "Ref Des/Silkscreen Bottom")
		(1 "F.Mask" user "Board Geometry/Soldermask Top")
		(3 "B.Mask" user "Board Geometry/Soldermask Bottom")
		(17 "Dwgs.User" user "User.Drawings")
		(19 "Cmts.User" user "User.Comments")
		(21 "Eco1.User" user "User.Eco1")
		(23 "Eco2.User" user "User.Eco2")
		(25 "Edge.Cuts" user "Board Geometry/Outline")
		(27 "Margin" user)
		(31 "F.CrtYd" user "Package Geometry/Place Bound Top")
		(29 "B.CrtYd" user "Package Geometry/Place Bound Bottom")
		(35 "F.Fab" user "Ref Des/Assembly Top")
		(33 "B.Fab" user "Ref Des/Assembly Bottom")
	)
	(footprint ""
		(layer "F.Cu")
		(at 59.649868 -295.89984)
		(property "Reference" "PEX0"
			(at -3.360166 35.566858 0)
			(unlocked yes)
			(layer "F.SilkS")
			(effects
				(font
					(size 2.032 1.524)
					(thickness 0.1524)
				)
				(justify left)
			)
		)
		(property "Value" ""
			(at 0 0 0)
			(layer "F.Fab")
			(effects
				(font
					(size 1.27 1.27)
				)
			)
		)
		(duplicate_pad_numbers_are_jumpers no)
		(pad "BC14" smd circle
			(at -10.450068 17.100042)
			(size 0.4572 0.4572)
			(layers "F.Cu" "F.Mask" "F.Paste")
			(net "GND")
		)
		(pad "BC15" smd circle
			(at -9.500108 17.100042)
			(size 0.4572 0.4572)
			(layers "F.Cu" "F.Mask" "F.Paste")
			(net "P5E_PEX0_STN2_TX_DP<41>")
		)
		(pad "BC16" smd circle
			(at -8.549894 17.100042)
			(size 0.4572 0.4572)
			(layers "F.Cu" "F.Mask" "F.Paste")
			(net "GND")
		)
		(pad "BC17" smd circle
			(at -7.599934 17.100042)
			(size 0.4572 0.4572)
			(layers "F.Cu" "F.Mask" "F.Paste")
			(net "P5E_PEX0_STN2_TX_DP<39>")
		)
		(pad "BC18" smd circle
			(at -6.649974 17.100042)
			(size 0.4572 0.4572)
			(layers "F.Cu" "F.Mask" "F.Paste")
			(net "GND")
		)
		(pad "BC19" smd circle
			(at -5.700014 17.100042)
			(size 0.4572 0.4572)
			(layers "F.Cu" "F.Mask" "F.Paste")
			(net "P5E_PEX0_STN2_TX_DP<37>")
		)
		(pad "BC20" smd circle
			(at -4.750054 17.100042)
			(size 0.4572 0.4572)
			(layers "F.Cu" "F.Mask" "F.Paste")
			(net "GND")
		)
		(pad "BC21" smd circle
			(at -3.800094 17.100042)
			(size 0.4572 0.4572)
			(layers "F.Cu" "F.Mask" "F.Paste")
			(net "P5E_PEX0_STN2_TX_DP<35>")
		)
		(pad "BC22" smd circle
			(at -2.84988 17.100042)
			(size 0.4572 0.4572)
			(layers "F.Cu" "F.Mask" "F.Paste")
			(net "GND")
		)
		(pad "BC23" smd circle
			(at -1.89992 17.100042)
			(size 0.4572 0.4572)
			(layers "F.Cu" "F.Mask" "F.Paste")
			(net "P5E_PEX0_STN2_TX_DP<33>")
		)
		(pad "BC24" smd circle
			(at -0.94996 17.100042)
			(size 0.4572 0.4572)
			(layers "F.Cu" "F.Mask" "F.Paste")
			(net "GND")
		)
		(pad "BC25" smd circle
			(at 0 17.100042)
			(size 0.4572 0.4572)
			(layers "F.Cu" "F.Mask" "F.Paste")
			(net "P5E_PEX0_STN1_TX_DP<16>")
		)
		(pad "BC26" smd circle
			(at 0.94996 17.100042)
			(size 0.4572 0.4572)
			(layers "F.Cu" "F.Mask" "F.Paste")
			(net "GND")
		)
		(pad "BC27" smd circle
			(at 1.89992 17.100042)
			(size 0.4572 0.4572)
			(layers "F.Cu" "F.Mask" "F.Paste")
			(net "P5E_PEX0_STN1_TX_DP<18>")
		)
		(pad "BC28" smd circle
			(at 2.84988 17.100042)
			(size 0.4572 0.4572)
			(layers "F.Cu" "F.Mask" "F.Paste")
			(net "GND")
		)
		(pad "BC29" smd circle
			(at 3.800094 17.100042)
			(size 0.4572 0.4572)
			(layers "F.Cu" "F.Mask" "F.Paste")
			(net "P5E_PEX0_STN1_TX_DP<20>")
		)
		(pad "BC30" smd circle
			(at 4.750054 17.100042)
			(size 0.4572 0.4572)
			(layers "F.Cu" "F.Mask" "F.Paste")
			(net "GND")
		)
		(pad "BC31" smd circle
			(at 5.700014 17.100042)
			(size 0.4572 0.4572)
			(layers "F.Cu" "F.Mask" "F.Paste")
			(net "P5E_PEX0_STN1_TX_DP<22>")
		)
		(pad "BC32" smd circle
			(at 6.649974 17.100042)
			(size 0.4572 0.4572)
			(layers "F.Cu" "F.Mask" "F.Paste")
			(net "GND")
		)
		(pad "BC33" smd circle
			(at 7.599934 17.100042)
			(size 0.4572 0.4572)
			(layers "F.Cu" "F.Mask" "F.Paste")
			(net "P5E_PEX0_STN1_TX_DP<24>")
		)
		(pad "BC34" smd circle
			(at 8.549894 17.100042)
			(size 0.4572 0.4572)
			(layers "F.Cu" "F.Mask" "F.Paste")
			(net "GND")
		)
		(pad "BC35" smd circle
			(at 9.500108 17.100042)
			(size 0.4572 0.4572)
			(layers "F.Cu" "F.Mask" "F.Paste")
			(net "P5E_PEX0_STN1_TX_DP<26>")
		)
		(pad "BC36" smd circle
			(at 10.450068 17.100042)
			(size 0.4572 0.4572)
			(layers "F.Cu" "F.Mask" "F.Paste")
			(net "GND")
		)
		(pad "BC37" smd circle
			(at 11.400028 17.100042)
			(size 0.4572 0.4572)
			(layers "F.Cu" "F.Mask" "F.Paste")
			(net "P5E_PEX0_STN1_TX_DP<28>")
		)
		(pad "BC38" smd circle
			(at 12.349988 17.100042)
			(size 0.4572 0.4572)
			(layers "F.Cu" "F.Mask" "F.Paste")
			(net "GND")
		)
		(pad "BC39" smd circle
			(at 13.299948 17.100042)
			(size 0.4572 0.4572)
			(layers "F.Cu" "F.Mask" "F.Paste")
			(net "P5E_PEX0_STN1_TX_DP<30>")
		)
		(pad "BC40" smd circle
			(at 14.249908 17.100042)
			(size 0.4572 0.4572)
			(layers "F.Cu" "F.Mask" "F.Paste")
			(net "GND")
		)
		(pad "BC41" smd circle
			(at 15.200122 17.100042)
			(size 0.4572 0.4572)
			(layers "F.Cu" "F.Mask" "F.Paste")
			(net "P5E_PEX0_STN0_TX_DP<15>")
		)
		(pad "BC42" smd circle
			(at 16.150082 17.100042)
			(size 0.4572 0.4572)
			(layers "F.Cu" "F.Mask" "F.Paste")
			(net "GND")
		)
		(pad "BC43" smd circle
			(at 17.100042 17.100042)
			(size 0.4572 0.4572)
			(layers "F.Cu" "F.Mask" "F.Paste")
			(net "P5E_PEX0_STN0_TX_DP<13>")
		)
		(pad "BC44" smd circle
			(at 18.050002 17.100042)
			(size 0.4572 0.4572)
			(layers "F.Cu" "F.Mask" "F.Paste")
			(net "GND")
		)
		(pad "BC45" smd circle
			(at 18.999962 17.100042)
			(size 0.4572 0.4572)
			(layers "F.Cu" "F.Mask" "F.Paste")
			(net "P5E_PEX0_STN0_TX_DP<11>")
		)
		(pad "BC46" smd circle
			(at 19.949922 17.100042)
			(size 0.4572 0.4572)
			(layers "F.Cu" "F.Mask" "F.Paste")
			(net "GND")
		)
		(pad "BC47" smd circle
			(at 20.899882 17.100042)
			(size 0.4572 0.4572)
			(layers "F.Cu" "F.Mask" "F.Paste")
			(net "P5E_PEX0_STN0_TX_DP<9>")
		)
		(pad "BC48" smd circle
			(at 21.850096 17.100042)
			(size 0.4572 0.4572)
			(layers "F.Cu" "F.Mask" "F.Paste")
			(net "GND")
		)
		(pad "BC49" smd circle
			(at 22.800056 17.100042)
			(size 0.4572 0.4572)
			(layers "F.Cu" "F.Mask" "F.Paste")
			(net "GND")
		)
		(pad "BD1" smd circle
			(at -22.800056 18.050002)
			(size 0.4572 0.4572)
			(layers "F.Cu" "F.Mask" "F.Paste")
			(net "GND")
		)
		(pad "BD2" smd circle
			(at -21.850096 18.050002)
			(size 0.4572 0.4572)
			(layers "F.Cu" "F.Mask" "F.Paste")
			(net "GND")
		)
		(pad "BD3" smd circle
			(at -20.899882 18.050002)
			(size 0.4572 0.4572)
			(layers "F.Cu" "F.Mask" "F.Paste")
			(net "Net_2746")
		)
		(pad "BD4" smd circle
			(at -19.949922 18.050002)
			(size 0.4572 0.4572)
			(layers "F.Cu" "F.Mask" "F.Paste")
			(net "GND")
		)
		(pad "BD5" smd circle
			(at -18.999962 18.050002)
			(size 0.4572 0.4572)
			(layers "F.Cu" "F.Mask" "F.Paste")
			(net "Net_2748")
		)
		(pad "BD6" smd circle
			(at -18.050002 18.050002)
			(size 0.4572 0.4572)
			(layers "F.Cu" "F.Mask" "F.Paste")
			(net "GND")
		)
		(pad "BD7" smd circle
			(at -17.100042 18.050002)
			(size 0.4572 0.4572)
			(layers "F.Cu" "F.Mask" "F.Paste")
			(net "Net_2750")
		)
		(pad "BD8" smd circle
			(at -16.150082 18.050002)
			(size 0.4572 0.4572)
			(layers "F.Cu" "F.Mask" "F.Paste")
			(net "GND")
		)
		(pad "BD9" smd circle
			(at -15.200122 18.050002)
			(size 0.4572 0.4572)
			(layers "F.Cu" "F.Mask" "F.Paste")
			(net "P5E_PEX0_STN2_TX_DN<47>")
		)
		(pad "BD10" smd circle
			(at -14.249908 18.050002)
			(size 0.4572 0.4572)
			(layers "F.Cu" "F.Mask" "F.Paste")
			(net "GND")
		)
		(pad "BD11" smd circle
			(at -13.299948 18.050002)
			(size 0.4572 0.4572)
			(layers "F.Cu" "F.Mask" "F.Paste")
			(net "P5E_PEX0_STN2_TX_DN<45>")
		)
		(pad "BD12" smd circle
			(at -12.349988 18.050002)
			(size 0.4572 0.4572)
			(layers "F.Cu" "F.Mask" "F.Paste")
			(net "GND")
		)
		(pad "BD13" smd circle
			(at -11.400028 18.050002)
			(size 0.4572 0.4572)
			(layers "F.Cu" "F.Mask" "F.Paste")
			(net "P5E_PEX0_STN2_TX_DN<43>")
		)
		(pad "BD14" smd circle
			(at -10.450068 18.050002)
			(size 0.4572 0.4572)
			(layers "F.Cu" "F.Mask" "F.Paste")
			(net "GND")
		)
		(pad "BD15" smd circle
			(at -9.500108 18.050002)
			(size 0.4572 0.4572)
			(layers "F.Cu" "F.Mask" "F.Paste")
			(net "P5E_PEX0_STN2_TX_DN<41>")
		)
		(pad "BD16" smd circle
			(at -8.549894 18.050002)
			(size 0.4572 0.4572)
			(layers "F.Cu" "F.Mask" "F.Paste")
			(net "GND")
		)
		(pad "BD17" smd circle
			(at -7.599934 18.050002)
			(size 0.4572 0.4572)
			(layers "F.Cu" "F.Mask" "F.Paste")
			(net "P5E_PEX0_STN2_TX_DN<39>")
		)
		(pad "BD18" smd circle
			(at -6.649974 18.050002)
			(size 0.4572 0.4572)
			(layers "F.Cu" "F.Mask" "F.Paste")
			(net "GND")
		)
		(pad "BD19" smd circle
			(at -5.700014 18.050002)
			(size 0.4572 0.4572)
			(layers "F.Cu" "F.Mask" "F.Paste")
			(net "P5E_PEX0_STN2_TX_DN<37>")
		)
		(pad "BD20" smd circle
			(at -4.750054 18.050002)
			(size 0.4572 0.4572)
			(layers "F.Cu" "F.Mask" "F.Paste")
			(net "GND")
		)
		(pad "BD21" smd circle
			(at -3.800094 18.050002)
			(size 0.4572 0.4572)
			(layers "F.Cu" "F.Mask" "F.Paste")
			(net "P5E_PEX0_STN2_TX_DN<35>")
		)
		(pad "BD22" smd circle
			(at -2.84988 18.050002)
			(size 0.4572 0.4572)
			(layers "F.Cu" "F.Mask" "F.Paste")
			(net "GND")
		)
		(pad "BD23" smd circle
			(at -1.89992 18.050002)
			(size 0.4572 0.4572)
			(layers "F.Cu" "F.Mask" "F.Paste")
			(net "P5E_PEX0_STN2_TX_DN<33>")
		)
		(pad "BD24" smd circle
			(at -0.94996 18.050002)
			(size 0.4572 0.4572)
			(layers "F.Cu" "F.Mask" "F.Paste")
			(net "GND")
		)
		(pad "BD25" smd circle
			(at 0 18.050002)
			(size 0.4572 0.4572)
			(layers "F.Cu" "F.Mask" "F.Paste")
			(net "P5E_PEX0_STN1_TX_DN<16>")
		)
		(pad "BD26" smd circle
			(at 0.94996 18.050002)
			(size 0.4572 0.4572)
			(layers "F.Cu" "F.Mask" "F.Paste")
			(net "GND")
		)
		(pad "BD27" smd circle
			(at 1.89992 18.050002)
			(size 0.4572 0.4572)
			(layers "F.Cu" "F.Mask" "F.Paste")
			(net "P5E_PEX0_STN1_TX_DN<18>")
		)
		(pad "BD28" smd circle
			(at 2.84988 18.050002)
			(size 0.4572 0.4572)
			(layers "F.Cu" "F.Mask" "F.Paste")
			(net "GND")
		)
		(pad "BD29" smd circle
			(at 3.800094 18.050002)
			(size 0.4572 0.4572)
			(layers "F.Cu" "F.Mask" "F.Paste")
			(net "P5E_PEX0_STN1_TX_DN<20>")
		)
		(pad "BD30" smd circle
			(at 4.750054 18.050002)
			(size 0.4572 0.4572)
			(layers "F.Cu" "F.Mask" "F.Paste")
			(net "GND")
		)
		(pad "BD31" smd circle
			(at 5.700014 18.050002)
			(size 0.4572 0.4572)
			(layers "F.Cu" "F.Mask" "F.Paste")
			(net "P5E_PEX0_STN1_TX_DN<22>")
		)
		(pad "BD32" smd circle
			(at 6.649974 18.050002)
			(size 0.4572 0.4572)
			(layers "F.Cu" "F.Mask" "F.Paste")
			(net "GND")
		)
		(pad "BD33" smd circle
			(at 7.599934 18.050002)
			(size 0.4572 0.4572)
			(layers "F.Cu" "F.Mask" "F.Paste")
			(net "P5E_PEX0_STN1_TX_DN<24>")
		)
		(pad "BD34" smd circle
			(at 8.549894 18.050002)
			(size 0.4572 0.4572)
			(layers "F.Cu" "F.Mask" "F.Paste")
			(net "GND")
		)
		(pad "BD35" smd circle
			(at 9.500108 18.050002)
			(size 0.4572 0.4572)
			(layers "F.Cu" "F.Mask" "F.Paste")
			(net "P5E_PEX0_STN1_TX_DN<26>")
		)
		(pad "BD36" smd circle
			(at 10.450068 18.050002)
			(size 0.4572 0.4572)
			(layers "F.Cu" "F.Mask" "F.Paste")
			(net "GND")
		)
		(pad "BD37" smd circle
			(at 11.400028 18.050002)
			(size 0.4572 0.4572)
			(layers "F.Cu" "F.Mask" "F.Paste")
			(net "P5E_PEX0_STN1_TX_DN<28>")
		)
		(pad "BD38" smd circle
			(at 12.349988 18.050002)
			(size 0.4572 0.4572)
			(layers "F.Cu" "F.Mask" "F.Paste")
			(net "GND")
		)
		(pad "BD39" smd circle
			(at 13.299948 18.050002)
			(size 0.4572 0.4572)
			(layers "F.Cu" "F.Mask" "F.Paste")
			(net "P5E_PEX0_STN1_TX_DN<30>")
		)
		(pad "BD40" smd circle
			(at 14.249908 18.050002)
			(size 0.4572 0.4572)
			(layers "F.Cu" "F.Mask" "F.Paste")
			(net "GND")
		)
		(pad "BD41" smd circle
			(at 15.200122 18.050002)
			(size 0.4572 0.4572)
			(layers "F.Cu" "F.Mask" "F.Paste")
			(net "P5E_PEX0_STN0_TX_DN<15>")
		)
		(pad "BD42" smd circle
			(at 16.150082 18.050002)
			(size 0.4572 0.4572)
			(layers "F.Cu" "F.Mask" "F.Paste")
			(net "GND")
		)
		(pad "BD43" smd circle
			(at 17.100042 18.050002)
			(size 0.4572 0.4572)
			(layers "F.Cu" "F.Mask" "F.Paste")
			(net "P5E_PEX0_STN0_TX_DN<13>")
		)
		(pad "BD44" smd circle
			(at 18.050002 18.050002)
			(size 0.4572 0.4572)
			(layers "F.Cu" "F.Mask" "F.Paste")
			(net "GND")
		)
		(pad "BD45" smd circle
			(at 18.999962 18.050002)
			(size 0.4572 0.4572)
			(layers "F.Cu" "F.Mask" "F.Paste")
			(net "P5E_PEX0_STN0_TX_DN<11>")
		)
		(pad "BD46" smd circle
			(at 19.949922 18.050002)
			(size 0.4572 0.4572)
			(layers "F.Cu" "F.Mask" "F.Paste")
			(net "GND")
		)
		(pad "BD47" smd circle
			(at 20.899882 18.050002)
			(size 0.4572 0.4572)
			(layers "F.Cu" "F.Mask" "F.Paste")
			(net "P5E_PEX0_STN0_TX_DN<9>")
		)
		(pad "BD48" smd circle
			(at 21.850096 18.050002)
			(size 0.4572 0.4572)
			(layers "F.Cu" "F.Mask" "F.Paste")
			(net "GND")
		)
		(pad "BD49" smd circle
			(at 22.800056 18.050002)
			(size 0.4572 0.4572)
			(layers "F.Cu" "F.Mask" "F.Paste")
			(net "GND")
		)
		(pad "BE1" smd circle
			(at -22.800056 18.999962)
			(size 0.4572 0.4572)
			(layers "F.Cu" "F.Mask" "F.Paste")
			(net "Net_2745")
		)
		(pad "BE2" smd circle
			(at -21.850096 18.999962)
			(size 0.4572 0.4572)
			(layers "F.Cu" "F.Mask" "F.Paste")
			(net "Net_2759")
		)
		(pad "BE3" smd circle
			(at -20.899882 18.999962)
			(size 0.4572 0.4572)
			(layers "F.Cu" "F.Mask" "F.Paste")
			(net "GND")
		)
		(pad "BE4" smd circle
			(at -19.949922 18.999962)
			(size 0.4572 0.4572)
			(layers "F.Cu" "F.Mask" "F.Paste")
			(net "GND")
		)
		(pad "BE5" smd circle
			(at -18.999962 18.999962)
			(size 0.4572 0.4572)
			(layers "F.Cu" "F.Mask" "F.Paste")
			(net "GND")
		)
		(pad "BE6" smd circle
			(at -18.050002 18.999962)
			(size 0.4572 0.4572)
			(layers "F.Cu" "F.Mask" "F.Paste")
			(net "GND")
		)
		(pad "BE7" smd circle
			(at -17.100042 18.999962)
			(size 0.4572 0.4572)
			(layers "F.Cu" "F.Mask" "F.Paste")
			(net "GND")
		)
		(pad "BE8" smd circle
			(at -16.150082 18.999962)
			(size 0.4572 0.4572)
			(layers "F.Cu" "F.Mask" "F.Paste")
			(net "GND")
		)
		(pad "BE9" smd circle
			(at -15.200122 18.999962)
			(size 0.4572 0.4572)
			(layers "F.Cu" "F.Mask" "F.Paste")
			(net "GND")
		)
		(pad "BE10" smd circle
			(at -14.249908 18.999962)
			(size 0.4572 0.4572)
			(layers "F.Cu" "F.Mask" "F.Paste")
			(net "GND")
		)
		(pad "BE11" smd circle
			(at -13.299948 18.999962)
			(size 0.4572 0.4572)
			(layers "F.Cu" "F.Mask" "F.Paste")
			(net "GND")
		)
		(pad "BE12" smd circle
			(at -12.349988 18.999962)
			(size 0.4572 0.4572)
			(layers "F.Cu" "F.Mask" "F.Paste")
			(net "GND")
		)
		(pad "BE13" smd circle
			(at -11.400028 18.999962)
			(size 0.4572 0.4572)
			(layers "F.Cu" "F.Mask" "F.Paste")
			(net "GND")
		)
		(pad "BE14" smd circle
			(at -10.450068 18.999962)
			(size 0.4572 0.4572)
			(layers "F.Cu" "F.Mask" "F.Paste")
			(net "GND")
		)
		(pad "BE15" smd circle
			(at -9.500108 18.999962)
			(size 0.4572 0.4572)
			(layers "F.Cu" "F.Mask" "F.Paste")
			(net "GND")
		)
		(pad "BE16" smd circle
			(at -8.549894 18.999962)
			(size 0.4572 0.4572)
			(layers "F.Cu" "F.Mask" "F.Paste")
			(net "GND")
		)
		(pad "BE17" smd circle
			(at -7.599934 18.999962)
			(size 0.4572 0.4572)
			(layers "F.Cu" "F.Mask" "F.Paste")
			(net "GND")
		)
		(pad "BE18" smd circle
			(at -6.649974 18.999962)
			(size 0.4572 0.4572)
			(layers "F.Cu" "F.Mask" "F.Paste")
			(net "GND")
		)
		(pad "BE19" smd circle
			(at -5.700014 18.999962)
			(size 0.4572 0.4572)
			(layers "F.Cu" "F.Mask" "F.Paste")
			(net "GND")
		)
		(pad "BE20" smd circle
			(at -4.750054 18.999962)
			(size 0.4572 0.4572)
			(layers "F.Cu" "F.Mask" "F.Paste")
			(net "GND")
		)
		(pad "BE21" smd circle
			(at -3.800094 18.999962)
			(size 0.4572 0.4572)
			(layers "F.Cu" "F.Mask" "F.Paste")
			(net "GND")
		)
		(pad "BE22" smd circle
			(at -2.84988 18.999962)
			(size 0.4572 0.4572)
			(layers "F.Cu" "F.Mask" "F.Paste")
			(net "GND")
		)
		(pad "BE23" smd circle
			(at -1.89992 18.999962)
			(size 0.4572 0.4572)
			(layers "F.Cu" "F.Mask" "F.Paste")
			(net "GND")
		)
		(pad "BE24" smd circle
			(at -0.94996 18.999962)
			(size 0.4572 0.4572)
			(layers "F.Cu" "F.Mask" "F.Paste")
			(net "GND")
		)
		(pad "BE25" smd circle
			(at 0 18.999962)
			(size 0.4572 0.4572)
			(layers "F.Cu" "F.Mask" "F.Paste")
			(net "GND")
		)
		(pad "BE26" smd circle
			(at 0.94996 18.999962)
			(size 0.4572 0.4572)
			(layers "F.Cu" "F.Mask" "F.Paste")
			(net "GND")
		)
		(pad "BE27" smd circle
			(at 1.89992 18.999962)
			(size 0.4572 0.4572)
			(layers "F.Cu" "F.Mask" "F.Paste")
			(net "GND")
		)
		(pad "BE28" smd circle
			(at 2.84988 18.999962)
			(size 0.4572 0.4572)
			(layers "F.Cu" "F.Mask" "F.Paste")
			(net "GND")
		)
		(pad "BE29" smd circle
			(at 3.800094 18.999962)
			(size 0.4572 0.4572)
			(layers "F.Cu" "F.Mask" "F.Paste")
			(net "GND")
		)
		(pad "BE30" smd circle
			(at 4.750054 18.999962)
			(size 0.4572 0.4572)
			(layers "F.Cu" "F.Mask" "F.Paste")
			(net "GND")
		)
		(pad "BE31" smd circle
			(at 5.700014 18.999962)
			(size 0.4572 0.4572)
			(layers "F.Cu" "F.Mask" "F.Paste")
			(net "GND")
		)
		(pad "BE32" smd circle
			(at 6.649974 18.999962)
			(size 0.4572 0.4572)
			(layers "F.Cu" "F.Mask" "F.Paste")
			(net "GND")
		)
	)
)
